FILE_TYPE = CONNECTIVITY;
{Allegro Design Entry HDL 17.4-2019 S026 (4007227) 1/17/2022}
"PAGE_NUMBER" = 169;
0"NC";
1"GND\g";
2"GND\g";
3"GND\g";
4"GND\g";
5"GND\g";
6"GND\g";
7"GND\g";
8"GND\g";
9"P5V_AUX\g";
10"P3V3_AUX\g";
11"GND\g";
12"GND\g";
13"GND\g";
14"GND\g";
15"PVDDCR_CPU0_P0_PVCC\g";
16"PVDDCR_CPU0_P0_VCC1";
17"GND\g";
18"SW_P12V_AUX_PVDDCR_CPU0_P0_FLT\g";
19"PVDDCR_CPU0_P0_VOS1";
20"SW_PVDDCR_CPU0_P0_PH1";
21"SW_PVDDCR_CPU0_P0_BOOT1";
22"SW_P12V_AUX_PVDDCR_CPU0_P0_FLT\g";
23"SW_PVDDCR_CPU0_P0_BOOT1_RC";
24"SW_PVDDCR_CPU0_P0_BOOT2";
25"SW_PVDDCR_CPU0_P0_BOOT2_RC";
26"PVDDCR_CPU0_P0_VCCS";
27"GND\g";
28"PVDDCR_CPU0_P0_PVCC\g";
29"PVDDCR_CPU0_P0_VCC2";
30"SW_PVDDCR_CPU0_P0_SW2";
31"SW_PVDDCR_CPU0_P0_PH2";
32"GND\g";
33"PVDDCR_CPU0_P0\g";
34"PVDDCR_CPU0_P0\g";
35"IND_CPU0_P0_CPL5";
36"IND_CPU0_P0_CPL1";
37"P12V_AUX\g";
38"SW_PVDDCR_CPU0_P0_SW1_RC";
39"PVDDCR_CPU0_P0_IMON1";
40"SW_PVDDCR_CPU0_P0_SW1";
41"NC_PVDDCR_CPU0_P0_GL1_2";
42"GND\g";
43"PVDDCR_CPU0_P0\g";
44"GND\g";
45"GND\g";
46"IND_CPU0_P0_CPL2";
47"IND_CPU0_P0_CPL1";
48"PVDDCR_CPU0_P0_PWM2";
49"PVDDCR_CPU0_P0_PWM1";
50"NC_PVDDCR_CPU0_P0_GL2_1";
51"NC_PVDDCR_CPU0_P0_GL1_1";
52"NC_PVDDCR_CPU0_P0_DNC1";
53"PVDDCR_CPU0_P0_LSET1";
54"SW_PVDDCR_CPU0_P0_SW2_RC";
55"NC_PVDDCR_CPU0_P0_GL2_2";
56"PVDDCR_CPU0_P0_TEMP0";
57"NC_PVDDCR_CPU0_P0_DNC2";
58"PVDDCR_CPU0_P0_IMON2";
59"PVDDCR_CPU0_P0_TEMP0";
60"PVDDCR_CPU0_P0_LSET2";
61"PVDDCR_CPU0_P0_VCCS";
62"PVDDCR_CPU0_P0_VOS2";
%"Q_RES"
"1","(-7350,1300)","0","pure_quanta","I10";
;
LOCATION"PR321"
$SEC"1"
CDS_SEC"1"
PACK_TYPE"0402LF"
WATTAGE"1/16W"
MATERIAL"EMPTY"
TOLERANCE"1%"
VALUE"8.87K"
CDS_LIB"pure_quanta"
PART_NUMBER"CS28872FB01";
"B"
$PN"2"60;
"A"
$PN"1"13;
%"Q_CAP"
"1","(-7650,1950)","0","pure_quanta","I14";
;
LOCATION"PC476"
$SEC"1"
CDS_SEC"1"
PACK_TYPE"C0402"
VOLTAGE"10V"
VALUE"2.2UF"
TOLERANCE"10%"
MATERIAL"X6S"
CDS_LIB"pure_quanta"
PART_NUMBER"CH5222KEB01";
"B"
$PN"2"1;
"A"
$PN"1"29;
%"UNIVERSAL_GND"
"1","(-7650,1750)","0","pure_quanta_power","I15";
;
CDS_LIB"pure_quanta_power"
HDL_POWER"GND";
"A"1;
%"ISL99390FRZTR5935"
"1","(-6175,1600)","0","pure_quanta","I16";
;
LOCATION"PU43"
$SEC"1"
CDS_SEC"1"
MATERIAL"IC"
VALUE"ISL99390FRZ-TR5935"
PART_TYPE"SMLF"
CDS_LMAN_SYM_OUTLINE"-300,700,250,-650"
CDS_LIB"pure_quanta"
NEEDS_NO_SIZE"TRUE"
PART_NUMBER"AL099390004";
"PGND2"
$PN"7_9-20_24"45;
"GL2"
$PN"41"55;
"GL1"
$PN"6"41;
"DNC"
$PN"31"57;
"EN"
$PN"35"29;
"PGND3"
$PN"40"45;
"VOS"
$PN"1"62;
"VIN2"
$PN"30"18;
"PGND1"
$PN"5"45;
"SW"
$PN"10_19"30;
"LSET"
$PN"37"60;
"IOUT"
$PN"38"58;
"TOUT_FLT"
$PN"36"59;
"PVCC"
$PN"4"28;
"PHASE"
$PN"32"31;
"VIN1"
$PN"25_29"18;
"BOOT"
$PN"33"24;
"AGND"
$PN"2"45;
"VCC"
$PN"3"29;
"REFIN"
$PN"39"61;
"PWM"
$PN"34"48;
%"Q_RES"
"2","(-7650,2450)","0","pure_quanta","I17";
;
LOCATION"PR319"
$SEC"1"
CDS_SEC"1"
PACK_TYPE"0402LF"
VALUE"2.2"
WATTAGE"1/16W"
MATERIAL"CHIP"
TOLERANCE"1%"
CDS_LIB"pure_quanta"
PART_NUMBER"CS-2202FB01";
"A"
$PN"1"28;
"B"
$PN"2"29;
%"UNIVERSAL_GND"
"1","(-7300,2200)","0","pure_quanta_power","I18";
;
CDS_LIB"pure_quanta_power"
HDL_POWER"GND";
"A"2;
%"Q_CAP"
"1","(-7300,2475)","0","pure_quanta","I19";
;
LOCATION"PC478_C0P0_2"
$SEC"1"
CDS_SEC"1"
VOLTAGE"10V"
VALUE"2.2UF"
PACK_TYPE"C0402"
TOLERANCE"10%"
MATERIAL"X6S"
CDS_LIB"pure_quanta"
PART_NUMBER"CH5222KEB01";
"B"
$PN"2"2;
"A"
$PN"1"28;
%"VCC_CORE"
"1","(-7650,2850)","0","pure_quanta_power","I20";
;
HDL_POWER"PVDDCR_CPU0_P0_PVCC"
CDS_LIB"pure_quanta_power";
"A"28;
%"UNIVERSAL_GND"
"1","(-8025,3800)","0","pure_quanta_power","I21";
;
CDS_LIB"pure_quanta_power"
HDL_POWER"GND";
"A"3;
%"Q_CAP"
"1","(-8025,4075)","0","pure_quanta","I22";
;
LOCATION"PC473_1"
$SEC"1"
CDS_SEC"1"
PACK_TYPE"0402"
VOLTAGE"25V"
TOLERANCE"10%"
MATERIAL"X7R"
VALUE"0.1UF"
CDS_LIB"pure_quanta"
PART_NUMBER"CH4104K1B00";
"B"
$PN"2"3;
"A"
$PN"1"26;
%"UNIVERSAL_GND"
"1","(-7675,3875)","0","pure_quanta_power","I24";
;
CDS_LIB"pure_quanta_power"
HDL_POWER"GND";
"A"4;
%"ISL99390FRZTR5935"
"1","(-6200,4350)","0","pure_quanta","I26";
;
LOCATION"PU6"
$SEC"1"
CDS_SEC"1"
VALUE"ISL99390FRZ-TR5935"
PART_TYPE"SMLF"
MATERIAL"IC"
NEEDS_NO_SIZE"TRUE"
CDS_LIB"pure_quanta"
CDS_LMAN_SYM_OUTLINE"-300,700,250,-650"
PART_NUMBER"AL099390004";
"PGND2"
$PN"7_9-20_24"27;
"GL2"
$PN"41"50;
"GL1"
$PN"6"51;
"DNC"
$PN"31"52;
"EN"
$PN"35"16;
"PGND3"
$PN"40"27;
"VOS"
$PN"1"19;
"VIN2"
$PN"30"22;
"PGND1"
$PN"5"27;
"SW"
$PN"10_19"40;
"LSET"
$PN"37"53;
"IOUT"
$PN"38"39;
"TOUT_FLT"
$PN"36"56;
"PVCC"
$PN"4"15;
"PHASE"
$PN"32"20;
"VIN1"
$PN"25_29"22;
"BOOT"
$PN"33"21;
"AGND"
$PN"2"27;
"VCC"
$PN"3"16;
"REFIN"
$PN"39"26;
"PWM"
$PN"34"49;
%"UNIVERSAL_GND"
"1","(-5625,875)","0","pure_quanta_power","I27";
;
CDS_LIB"pure_quanta_power"
HDL_POWER"GND";
"A"45;
%"Q_RES"
"2","(-4650,975)","0","pure_quanta","I28";
;
LOCATION"PR496"
$SEC"1"
CDS_SEC"1"
PACK_TYPE"0402LF"
VALUE"1.5"
TOLERANCE"1%"
MATERIAL"EMPTY"
WATTAGE"1/8W"
CDS_LIB"pure_quanta"
PART_NUMBER"CS-1504FB00";
"A"
$PN"1"54;
"B"
$PN"2"5;
%"UNIVERSAL_GND"
"1","(-4650,750)","0","pure_quanta_power","I29";
;
CDS_LIB"pure_quanta_power"
HDL_POWER"GND";
"A"5;
%"Q_RES"
"1","(-8625,5625)","1","pure_quanta","I3";
;
LOCATION"PR445"
$SEC"1"
CDS_SEC"1"
WATTAGE"1/16W"
MATERIAL"CHIP"
TOLERANCE"5%"
VALUE"0"
PACK_TYPE"0402LF"
CDS_LIB"pure_quanta"
PART_NUMBER"CS00002JB13";
"B"
$PN"2"9;
"A"
$PN"1"15;
%"Q_RES"
"1","(-4250,675)","0","pure_quanta","I30";
;
LOCATION"PR325"
$SEC"1"
CDS_SEC"1"
WATTAGE"1/16W"
MATERIAL"CHIP"
TOLERANCE"5%"
VALUE"0"
PACK_TYPE"0402LF"
CDS_LIB"pure_quanta"
PART_NUMBER"CS00002JB13";
"B"
$PN"2"43;
"A"
$PN"1"62;
%"Q_CAP"
"1","(-4650,1425)","0","pure_quanta","I31";
;
LOCATION"PC179"
$SEC"1"
CDS_SEC"1"
TOLERANCE"10%"
VOLTAGE"50V"
MATERIAL"EMPTY"
PACK_TYPE"C0402"
VALUE"560PF"
CDS_LIB"pure_quanta"
PART_NUMBER"CH1566K1B09";
"B"
$PN"2"54;
"A"
$PN"1"30;
%"Q_RES"
"1","(-4725,1950)","0","pure_quanta","I32";
;
LOCATION"PR323"
$SEC"1"
CDS_SEC"1"
MATERIAL"CHIP"
TOLERANCE"1%"
PACK_TYPE"0402LF"
WATTAGE"1/16W"
VALUE"5.6"
CDS_LIB"pure_quanta"
PART_NUMBER"CS-5602FB01";
"B"
$PN"2"25;
"A"
$PN"1"24;
%"Q_CAP"
"1","(-5550,2475)","0","pure_quanta","I33";
;
LOCATION"PC482_2"
$SEC"1"
CDS_SEC"1"
VALUE"0.1UF"
VOLTAGE"25V"
PACK_TYPE"0402"
MATERIAL"X7R"
TOLERANCE"10%"
CDS_LIB"pure_quanta"
PART_NUMBER"CH4104K1B00";
"B"
$PN"2"17;
"A"
$PN"1"18;
%"Q_CAP"
"1","(-5225,2475)","0","pure_quanta","I34";
;
LOCATION"PC480_2"
$SEC"1"
CDS_SEC"1"
TOLERANCE"10%"
MATERIAL"X6S"
VALUE"1UF"
VOLTAGE"25V"
PACK_TYPE"C0402"
CDS_LIB"pure_quanta"
PART_NUMBER"CH5104KEB02";
"B"
$PN"2"17;
"A"
$PN"1"18;
%"UNIVERSAL_GND"
"1","(-5625,3625)","0","pure_quanta_power","I35";
;
CDS_LIB"pure_quanta_power"
HDL_POWER"GND";
"A"27;
%"Q_CAP"
"1","(-4900,2475)","0","pure_quanta","I36";
;
LOCATION"PC484_2"
$SEC"1"
CDS_SEC"1"
PACK_TYPE"C0805"
VOLTAGE"16V"
TOLERANCE"20%"
VALUE"22UF"
MATERIAL"X6S"
CDS_LIB"pure_quanta"
PART_NUMBER"CH6223MEA01";
"B"
$PN"2"17;
"A"
$PN"1"18;
%"Q_CAP"
"1","(-4575,2475)","0","pure_quanta","I37";
;
LOCATION"PC486_2"
$SEC"1"
CDS_SEC"1"
PACK_TYPE"C0805"
VALUE"22UF"
TOLERANCE"20%"
VOLTAGE"16V"
MATERIAL"X6S"
CDS_LIB"pure_quanta"
PART_NUMBER"CH6223MEA01";
"B"
$PN"2"17;
"A"
$PN"1"18;
%"UNIVERSAL_GND"
"1","(-4275,2125)","0","pure_quanta_power","I38";
;
CDS_LIB"pure_quanta_power"
HDL_POWER"GND";
"A"17;
%"Q_CAP"
"1","(-4275,2475)","0","pure_quanta","I39";
;
LOCATION"PC488_2"
$SEC"1"
CDS_SEC"1"
TOLERANCE"20%"
MATERIAL"X6S"
PACK_TYPE"C0805"
VOLTAGE"16V"
VALUE"22UF"
CDS_LIB"pure_quanta"
PART_NUMBER"CH6223MEA01";
"B"
$PN"2"17;
"A"
$PN"1"18;
%"Q_RES"
"1","(-8275,5625)","1","pure_quanta","I4";
;
LOCATION"PR446"
$SEC"1"
CDS_SEC"1"
MATERIAL"EMPTY"
WATTAGE"1/16W"
TOLERANCE"5%"
VALUE"0"
PACK_TYPE"0402LF"
CDS_LIB"pure_quanta"
PART_NUMBER"CS00002JB13";
"B"
$PN"2"10;
"A"
$PN"1"15;
%"VCC_CORE"
"1","(-4275,2775)","0","pure_quanta_power","I40";
;
HDL_POWER"SW_P12V_AUX_PVDDCR_CPU0_P0_FLT"
CDS_LIB"pure_quanta_power";
"A"18;
%"UNIVERSAL_GND"
"1","(-4825,3500)","0","pure_quanta_power","I41";
;
CDS_LIB"pure_quanta_power"
HDL_POWER"GND";
"A"6;
%"Q_RES"
"2","(-4825,3725)","0","pure_quanta","I42";
;
LOCATION"PR495"
$SEC"1"
CDS_SEC"1"
TOLERANCE"1%"
VALUE"1.5"
MATERIAL"EMPTY"
WATTAGE"1/8W"
PACK_TYPE"0402LF"
CDS_LIB"pure_quanta"
PART_NUMBER"CS-1504FB00";
"A"
$PN"1"38;
"B"
$PN"2"6;
%"Q_RES"
"1","(-4375,3400)","0","pure_quanta","I43";
;
LOCATION"PR324"
$SEC"1"
CDS_SEC"1"
TOLERANCE"5%"
WATTAGE"1/16W"
VALUE"0"
MATERIAL"CHIP"
PACK_TYPE"0402LF"
CDS_LIB"pure_quanta"
PART_NUMBER"CS00002JB13";
"B"
$PN"2"34;
"A"
$PN"1"19;
%"UNIVERSAL_GND"
"1","(-7975,4500)","0","pure_quanta_power","I44";
;
CDS_LIB"pure_quanta_power"
HDL_POWER"GND";
"A"7;
%"Q_CAP"
"1","(-7975,4700)","0","pure_quanta","I45";
;
LOCATION"PC475"
$SEC"1"
CDS_SEC"1"
VOLTAGE"10V"
VALUE"2.2UF"
TOLERANCE"10%"
MATERIAL"X6S"
PACK_TYPE"C0402"
CDS_LIB"pure_quanta"
PART_NUMBER"CH5222KEB01";
"B"
$PN"2"7;
"A"
$PN"1"16;
%"Q_RES"
"1","(-7350,4050)","0","pure_quanta","I46";
;
LOCATION"PR320"
$SEC"1"
CDS_SEC"1"
TOLERANCE"1%"
VALUE"8.87K"
WATTAGE"1/16W"
PACK_TYPE"0402LF"
MATERIAL"EMPTY"
CDS_LIB"pure_quanta"
PART_NUMBER"CS28872FB01";
"B"
$PN"2"53;
"A"
$PN"1"4;
%"UNIVERSAL_GND"
"1","(-7625,4950)","0","pure_quanta_power","I48";
;
CDS_LIB"pure_quanta_power"
HDL_POWER"GND";
"A"8;
%"Q_RES"
"2","(-7975,5200)","0","pure_quanta","I49";
;
LOCATION"PR318"
$SEC"1"
CDS_SEC"1"
WATTAGE"1/16W"
MATERIAL"CHIP"
TOLERANCE"1%"
VALUE"2.2"
PACK_TYPE"0402LF"
CDS_LIB"pure_quanta"
PART_NUMBER"CS-2202FB01";
"A"
$PN"1"15;
"B"
$PN"2"16;
%"VCC_CORE"
"1","(-8625,5825)","0","pure_quanta_power","I5";
;
HDL_POWER"P5V_AUX"
CDS_LIB"pure_quanta_power";
"A"9;
%"VCC_CORE"
"1","(-7800,5825)","0","pure_quanta_power","I50";
;
HDL_POWER"PVDDCR_CPU0_P0_PVCC"
CDS_LIB"pure_quanta_power";
"A"15;
%"Q_CAP"
"1","(-7625,5200)","0","pure_quanta","I51";
;
LOCATION"PC477_C0P0_1"
$SEC"1"
CDS_SEC"1"
VOLTAGE"10V"
VALUE"2.2UF"
TOLERANCE"10%"
MATERIAL"X6S"
PACK_TYPE"C0402"
CDS_LIB"pure_quanta"
PART_NUMBER"CH5222KEB01";
"B"
$PN"2"8;
"A"
$PN"1"15;
%"Q_CAP"
"1","(-5550,5225)","0","pure_quanta","I52";
;
LOCATION"PC479_1"
$SEC"1"
CDS_SEC"1"
MATERIAL"X7R"
VALUE"0.1UF"
VOLTAGE"25V"
PACK_TYPE"0402"
TOLERANCE"10%"
CDS_LIB"pure_quanta"
PART_NUMBER"CH4104K1B00";
"B"
$PN"2"14;
"A"
$PN"1"22;
%"Q_CAP"
"1","(-5225,5225)","0","pure_quanta","I53";
;
LOCATION"PC481_1"
$SEC"1"
CDS_SEC"1"
VALUE"1UF"
VOLTAGE"25V"
TOLERANCE"10%"
MATERIAL"X6S"
PACK_TYPE"C0402"
CDS_LIB"pure_quanta"
PART_NUMBER"CH5104KEB02";
"B"
$PN"2"14;
"A"
$PN"1"22;
%"Q_CAP"
"1","(-4825,4175)","0","pure_quanta","I54";
;
LOCATION"PC178"
$SEC"1"
CDS_SEC"1"
VALUE"560PF"
MATERIAL"EMPTY"
VOLTAGE"50V"
TOLERANCE"10%"
PACK_TYPE"C0402"
CDS_LIB"pure_quanta"
PART_NUMBER"CH1566K1B09";
"B"
$PN"2"38;
"A"
$PN"1"40;
%"Q_RES"
"1","(-4850,4700)","0","pure_quanta","I55";
;
LOCATION"PR322"
$SEC"1"
CDS_SEC"1"
WATTAGE"1/16W"
TOLERANCE"1%"
VALUE"5.6"
MATERIAL"CHIP"
PACK_TYPE"0402LF"
CDS_LIB"pure_quanta"
PART_NUMBER"CS-5602FB01";
"B"
$PN"2"23;
"A"
$PN"1"21;
%"Q_CAP"
"1","(-4900,5225)","0","pure_quanta","I57";
;
LOCATION"PC483_1"
$SEC"1"
CDS_SEC"1"
PACK_TYPE"C0805"
VOLTAGE"16V"
VALUE"22UF"
TOLERANCE"20%"
MATERIAL"X6S"
CDS_LIB"pure_quanta"
PART_NUMBER"CH6223MEA01";
"B"
$PN"2"14;
"A"
$PN"1"22;
%"Q_CAP"
"1","(-4575,5225)","0","pure_quanta","I58";
;
LOCATION"PC485_1"
$SEC"1"
CDS_SEC"1"
PACK_TYPE"C0805"
VALUE"22UF"
TOLERANCE"20%"
VOLTAGE"16V"
MATERIAL"X6S"
CDS_LIB"pure_quanta"
PART_NUMBER"CH6223MEA01";
"B"
$PN"2"14;
"A"
$PN"1"22;
%"Q_CAP"
"1","(-4275,5225)","0","pure_quanta","I59";
;
LOCATION"PC487_1"
$SEC"1"
CDS_SEC"1"
VALUE"22UF"
VOLTAGE"16V"
MATERIAL"X6S"
PACK_TYPE"C0805"
TOLERANCE"20%"
CDS_LIB"pure_quanta"
PART_NUMBER"CH6223MEA01";
"B"
$PN"2"14;
"A"
$PN"1"22;
%"VCC_CORE"
"1","(-8275,5825)","0","pure_quanta_power","I6";
;
HDL_POWER"P3V3_AUX"
CDS_LIB"pure_quanta_power";
"A"10;
%"Q_CAP"
"1","(-3750,1825)","0","pure_quanta","I61";
;
LOCATION"PC490"
$SEC"1"
CDS_SEC"1"
PACK_TYPE"0402"
MATERIAL"X7R"
VALUE"0.22UF"
VOLTAGE"16V"
TOLERANCE"10%"
CDS_LIB"pure_quanta"
PART_NUMBER"CH4223K1B00";
"B"
$PN"2"31;
"A"
$PN"1"25;
%"Q_INDUCTOR4P_14"
"1","(-3075,1475)","0","pure_quanta","I62";
;
LOCATION"PL52"
$SEC"1"
CDS_SEC"1"
VALUE"150NH"
MATERIAL"IND"
PART_TYPE"SMLF"
CDS_LIB"pure_quanta"
NEEDS_NO_SIZE"TRUE"
PART_NUMBER"CV+15^0TZ04";
"1"
$PN"1"30;
"4"
$PN"4"43;
"3"
$PN"3"46;
"2"
$PN"2"47;
%"Q_CAPP"
"1","(-3175,2800)","0","pure_quanta","I64";
;
LOCATION"PC108"
$SEC"1"
CDS_SEC"1"
VOLTAGE"4V"
PACK_TYPE"SMLF"
MATERIAL"SPCAP"
TOLERANCE"20%"
VALUE"220UF"
CDS_LIB"pure_quanta"
PART_NUMBER"CH122KM8801";
"A"
$PN"1"33;
"B"
$PN"2"32;
%"Q_CAPP"
"1","(-2825,2800)","0","pure_quanta","I65";
;
LOCATION"PC494"
$SEC"1"
CDS_SEC"1"
TOLERANCE"20%"
VALUE"220UF"
VOLTAGE"4V"
MATERIAL"SPCAP"
PACK_TYPE"SMLF"
CDS_LIB"pure_quanta"
PART_NUMBER"CH122KM8801";
"A"
$PN"1"33;
"B"
$PN"2"32;
%"Q_CAPP"
"1","(-2500,2800)","0","pure_quanta","I66";
;
LOCATION"PC495"
$SEC"1"
CDS_SEC"1"
PACK_TYPE"SMLF"
MATERIAL"SPCAP"
VALUE"220UF"
TOLERANCE"20%"
VOLTAGE"4V"
CDS_LIB"pure_quanta"
PART_NUMBER"CH122KM8801";
"A"
$PN"1"33;
"B"
$PN"2"32;
%"Q_CAPP"
"1","(-2175,2800)","0","pure_quanta","I67";
;
LOCATION"PC496"
$SEC"1"
CDS_SEC"1"
VALUE"220UF"
VOLTAGE"4V"
PACK_TYPE"SMLF"
TOLERANCE"20%"
MATERIAL"SPCAP"
CDS_LIB"pure_quanta"
PART_NUMBER"CH122KM8801";
"A"
$PN"1"33;
"B"
$PN"2"32;
%"Q_CAP"
"1","(-1725,1425)","0","pure_quanta","I68";
;
LOCATION"PC499_2"
$SEC"1"
CDS_SEC"1"
VALUE"22UF"
VOLTAGE"4V"
PACK_TYPE"C0805"
MATERIAL"X6S"
TOLERANCE"20%"
CDS_LIB"pure_quanta"
PART_NUMBER"CH622KMEA03";
"B"
$PN"2"44;
"A"
$PN"1"43;
%"UNIVERSAL_GND"
"1","(-1300,1075)","0","pure_quanta_power","I69";
;
CDS_LIB"pure_quanta_power"
HDL_POWER"GND";
"A"44;
%"UNIVERSAL_GND"
"1","(-8000,1050)","0","pure_quanta_power","I7";
;
CDS_LIB"pure_quanta_power"
HDL_POWER"GND";
"A"11;
%"Q_CAP"
"1","(-1300,1425)","0","pure_quanta","I70";
;
LOCATION"PC501_2"
$SEC"1"
CDS_SEC"1"
PACK_TYPE"C0805"
MATERIAL"X6S"
TOLERANCE"20%"
VALUE"22UF"
VOLTAGE"4V"
CDS_LIB"pure_quanta"
PART_NUMBER"CH622KMEA03";
"B"
$PN"2"44;
"A"
$PN"1"43;
%"VCC_CORE"
"1","(-1300,1750)","0","pure_quanta_power","I71";
;
HDL_POWER"PVDDCR_CPU0_P0"
CDS_LIB"pure_quanta_power";
"A"43;
%"UNIVERSAL_GND"
"1","(-1875,2425)","0","pure_quanta_power","I72";
;
CDS_LIB"pure_quanta_power"
HDL_POWER"GND";
"A"32;
%"Q_CAPP"
"1","(-1900,2800)","0","pure_quanta","I73";
;
LOCATION"PC498"
$SEC"1"
CDS_SEC"1"
TOLERANCE"20%"
MATERIAL"SPCAP"
PACK_TYPE"SMLF"
VALUE"220UF"
VOLTAGE"4V"
CDS_LIB"pure_quanta"
PART_NUMBER"CH122KM8801";
"A"
$PN"1"33;
"B"
$PN"2"32;
%"VCC_CORE"
"1","(-1875,3100)","0","pure_quanta_power","I74";
;
HDL_POWER"PVDDCR_CPU0_P0"
CDS_LIB"pure_quanta_power";
"A"33;
%"UNIVERSAL_GND"
"1","(-775,3800)","0","pure_quanta_power","I75";
;
CDS_LIB"pure_quanta_power"
HDL_POWER"GND";
"A"42;
%"Q_CAP"
"1","(-4000,4575)","0","pure_quanta","I76";
;
LOCATION"PC489"
$SEC"1"
CDS_SEC"1"
PACK_TYPE"0402"
MATERIAL"X7R"
VOLTAGE"16V"
TOLERANCE"10%"
VALUE"0.22UF"
CDS_LIB"pure_quanta"
PART_NUMBER"CH4223K1B00";
"B"
$PN"2"20;
"A"
$PN"1"23;
%"Q_INDUCTOR4P_14"
"1","(-3250,4225)","0","pure_quanta","I77";
;
LOCATION"PL51"
$SEC"1"
CDS_SEC"1"
PART_TYPE"SMLF"
VALUE"150NH"
MATERIAL"IND"
CDS_LIB"pure_quanta"
NEEDS_NO_SIZE"TRUE"
PART_NUMBER"CV+15^0TZ04";
"1"
$PN"1"40;
"4"
$PN"4"34;
"3"
$PN"3"36;
"2"
$PN"2"35;
%"UNIVERSAL_GND"
"1","(-4025,4900)","0","pure_quanta_power","I78";
;
CDS_LIB"pure_quanta_power"
HDL_POWER"GND";
"A"14;
%"Q_CAPP"
"1","(-3950,5225)","0","pure_quanta","I79";
;
LOCATION"PC491"
$SEC"1"
CDS_SEC"1"
VOLTAGE"16V"
MATERIAL"OSCON"
PACK_TYPE"THLF"
TOLERANCE"20%"
VALUE"270UF"
CDS_LIB"pure_quanta"
PART_NUMBER"CC72703MD38";
"A"
$PN"1"22;
"B"
$PN"2"14;
%"Q_CAP"
"1","(-8000,1325)","0","pure_quanta","I8";
;
LOCATION"PC474_2"
$SEC"1"
CDS_SEC"1"
PACK_TYPE"0402"
VOLTAGE"25V"
VALUE"0.1UF"
TOLERANCE"10%"
MATERIAL"X7R"
CDS_LIB"pure_quanta"
PART_NUMBER"CH4104K1B00";
"B"
$PN"2"11;
"A"
$PN"1"61;
%"VCC_CORE"
"1","(-4025,5500)","0","pure_quanta_power","I80";
;
HDL_POWER"SW_P12V_AUX_PVDDCR_CPU0_P0_FLT"
CDS_LIB"pure_quanta_power";
"A"22;
%"Q_CAPP"
"1","(-3525,5225)","0","pure_quanta","I81";
;
LOCATION"PC492"
$SEC"1"
CDS_SEC"1"
TOLERANCE"20%"
VALUE"270UF"
VOLTAGE"16V"
MATERIAL"OSCON"
PACK_TYPE"THLF"
CDS_LIB"pure_quanta"
PART_NUMBER"CC72703MD38";
"A"
$PN"1"22;
"B"
$PN"2"14;
%"Q_INDUCTOR"
"1","(-3075,5425)","0","pure_quanta","I82";
;
LOCATION"PL53"
$SEC"1"
CDS_SEC"1"
VALUE"50NH/86A"
PACK_TYPE"SMLF"
MATERIAL"IND"
CDS_LIB"pure_quanta"
NEEDS_NO_SIZE"TRUE"
PART_NUMBER"CVA50^0MZ09";
"1"
$PN"1"22;
"2"
$PN"2"37;
%"UNIVERSAL_GND"
"1","(-2700,4950)","0","pure_quanta_power","I83";
;
CDS_LIB"pure_quanta_power"
HDL_POWER"GND";
"A"12;
%"Q_CAP"
"1","(-2700,5250)","0","pure_quanta","I85";
;
LOCATION"PC479"
$SEC"1"
CDS_SEC"1"
TOLERANCE"10%"
PACK_TYPE"0402"
MATERIAL"X7R"
VOLTAGE"25V"
VALUE"0.1UF"
CDS_LIB"pure_quanta"
PART_NUMBER"CH4104K1B00";
"B"
$PN"2"12;
"A"
$PN"1"37;
%"VCC_CORE"
"1","(-2700,5500)","0","pure_quanta_power","I86";
;
HDL_POWER"P12V_AUX"
CDS_LIB"pure_quanta_power";
"A"37;
%"Q_CAP"
"1","(-2000,4175)","0","pure_quanta","I87";
;
LOCATION"PC497"
$SEC"1"
CDS_SEC"1"
TOLERANCE"10%"
MATERIAL"X7R"
PACK_TYPE"0402"
VOLTAGE"25V"
VALUE"0.1UF"
CDS_LIB"pure_quanta"
PART_NUMBER"CH4104K1B00";
"B"
$PN"2"42;
"A"
$PN"1"34;
%"Q_CAP"
"1","(-1625,4175)","0","pure_quanta","I88";
;
LOCATION"PC500_1"
$SEC"1"
CDS_SEC"1"
TOLERANCE"20%"
PACK_TYPE"C0805"
MATERIAL"X6S"
VALUE"22UF"
VOLTAGE"4V"
CDS_LIB"pure_quanta"
PART_NUMBER"CH622KMEA03";
"B"
$PN"2"42;
"A"
$PN"1"34;
%"Q_CAP"
"1","(-1175,4175)","0","pure_quanta","I89";
;
LOCATION"PC502_1"
$SEC"1"
CDS_SEC"1"
VOLTAGE"4V"
PACK_TYPE"C0805"
MATERIAL"X6S"
TOLERANCE"20%"
VALUE"22UF"
CDS_LIB"pure_quanta"
PART_NUMBER"CH622KMEA03";
"B"
$PN"2"42;
"A"
$PN"1"34;
%"UNIVERSAL_GND"
"1","(-7675,1125)","0","pure_quanta_power","I9";
;
CDS_LIB"pure_quanta_power"
HDL_POWER"GND";
"A"13;
%"Q_RES"
"2","(-775,4150)","0","pure_quanta","I90";
;
LOCATION"PR447"
$SEC"1"
CDS_SEC"1"
WATTAGE"1/16W"
MATERIAL"CHIP"
TOLERANCE"1%"
VALUE"1K"
PACK_TYPE"0402LF"
CDS_LIB"pure_quanta"
PART_NUMBER"CS21002FB06";
"A"
$PN"1"34;
"B"
$PN"2"42;
%"VCC_CORE"
"1","(-775,4525)","0","pure_quanta_power","I91";
;
HDL_POWER"PVDDCR_CPU0_P0"
CDS_LIB"pure_quanta_power";
"A"34;
END.
